# BASEBOARD_FAB2 (Tioga Pass) — schematic netlist excerpt (pin names and nets, part order shuffled) for the footprints in the layout excerpt that follows; sources: Cadence DE-HDL packaged netlist, KiCad conversion of Wiwynn_Tioga_Pass_MB.brd

R7W6  RES  0.0 5% CHIP  pkg 0402  page 118 : A = FM_BATTERY_SENSE_EN_N ; B = FM_BATTERY_SENSE_EN_R_N
C5P22  CAP  47UF 4V 20% X6S  pkg 0805  page 42 : A = PVCCIN_CPU0 ; B = GND
C8P21  CAP  47UF 4V 20% X6S  pkg 0805  page 76 : A = PVCCIN_CPU1 ; B = GND

(kicad_pcb
	(version 20260206)
	(generator "pcbnew")
	(generator_version "10.0")
	(general
		(thickness 1.6)
		(legacy_teardrops no)
	)
	(paper "A4")
	(title_block
		(title "Wiwynn_Tioga_Pass_MB.brd")
		(comment 1 "Tioga Pass / footprints 2739-2741 of 4770")
	)
	(layers
		(0 "F.Cu" signal "TOP")
		(4 "In1.Cu" signal "L2GND")
		(6 "In2.Cu" signal "L3")
		(8 "In3.Cu" signal "L4GND")
		(10 "In4.Cu" signal "L5")
		(12 "In5.Cu" signal "L6GND")
		(14 "In6.Cu" signal "L7VCC")
		(16 "In7.Cu" signal "L8VCC")
		(18 "In8.Cu" signal "L9GND")
		(20 "In9.Cu" signal "L10")
		(22 "In10.Cu" signal "L11GND")
		(24 "In11.Cu" signal "L12")
		(26 "In12.Cu" signal "L13GND")
		(2 "B.Cu" signal "BOTTOM")
		(9 "F.Adhes" user "F.Adhesive")
		(11 "B.Adhes" user "B.Adhesive")
		(13 "F.Paste" user "Package Geometry/Pastemask Top")
		(15 "B.Paste" user "Package Geometry/Pastemask Bottom")
		(5 "F.SilkS" user "Ref Des/Silkscreen Top")
		(7 "B.SilkS" user "Ref Des/Silkscreen Bottom")
		(1 "F.Mask" user "Board Geometry/Soldermask Top")
		(3 "B.Mask" user "Board Geometry/Soldermask Bottom")
		(17 "Dwgs.User" user "User.Drawings")
		(19 "Cmts.User" user "User.Comments")
		(21 "Eco1.User" user "User.Eco1")
		(23 "Eco2.User" user "User.Eco2")
		(25 "Edge.Cuts" user "Board Geometry/Outline")
		(27 "Margin" user)
		(31 "F.CrtYd" user "Package Geometry/Place Bound Top")
		(29 "B.CrtYd" user "Package Geometry/Place Bound Bottom")
		(35 "F.Fab" user "Ref Des/Assembly Top")
		(33 "B.Fab" user "Ref Des/Assembly Bottom")
	)
	(footprint ""
		(layer "B.Cu")
		(at 93.548454 -77.82814)
		(property "Reference" "C8P21"
			(at 0 0 0)
			(layer "B.SilkS")
			(hide yes)
			(effects
				(font
					(size 1.27 1.27)
				)
				(justify mirror)
			)
		)
		(property "Value" ""
			(at 0 0 0)
			(layer "B.Fab")
			(effects
				(font
					(size 1.27 1.27)
				)
				(justify mirror)
			)
		)
		(duplicate_pad_numbers_are_jumpers no)
		(fp_poly
			(pts
				(xy 0.7239 -0.2159) (xy -0.7239 -0.2159) (xy -0.7239 1.9939) (xy 0.7239 1.9939)
			)
			(stroke
				(width 0)
				(type default)
			)
			(fill no)
			(layer "B.CrtYd")
		)
		(fp_line
			(start -0.7239 -0.2159)
			(end 0.7239 -0.2159)
			(stroke
				(width 0.1)
				(type default)
			)
			(layer "B.Fab")
		)
		(fp_line
			(start -0.7239 1.9939)
			(end -0.7239 -0.2159)
			(stroke
				(width 0.1)
				(type default)
			)
			(layer "B.Fab")
		)
		(fp_line
			(start 0.7239 -0.2159)
			(end 0.7239 1.9939)
			(stroke
				(width 0.1)
				(type default)
			)
			(layer "B.Fab")
		)
		(fp_line
			(start 0.7239 1.9939)
			(end -0.7239 1.9939)
			(stroke
				(width 0.1)
				(type default)
			)
			(layer "B.Fab")
		)
		(pad "1" smd rect
			(at 0 0 180)
			(size 1.27 1.016)
			(layers "B.Cu" "B.Mask" "B.Paste")
			(net "PVCCIN_CPU1")
		)
		(pad "2" smd rect
			(at 0 1.778 180)
			(size 1.27 1.016)
			(layers "B.Cu" "B.Mask" "B.Paste")
			(net "GND")
		)
		(zone
			(layer "B.Cu")
			(hatch none 0.5)
			(connect_pads
				(clearance 0)
			)
			(min_thickness 0.25)
			(keepout
				(tracks not_allowed)
				(vias allowed)
				(pads allowed)
				(copperpour not_allowed)
				(footprints allowed)
			)
			(placement
				(enabled no)
				(sheetname "")
			)
			(fill
				(thermal_gap 0.5)
				(thermal_bridge_width 0.5)
				(island_removal_mode 0)
			)
			(polygon
				(pts
					(xy 94.183454 -77.32014) (xy 92.913454 -77.32014) (xy 92.913454 -76.55814) (xy 94.183454 -76.55814)
				)
			)
		)
	)
	(footprint ""
		(layer "B.Cu")
		(at 267.692886 -77.82814)
		(property "Reference" "C5P22"
			(at 0 0 0)
			(layer "B.SilkS")
			(hide yes)
			(effects
				(font
					(size 1.27 1.27)
				)
				(justify mirror)
			)
		)
		(property "Value" ""
			(at 0 0 0)
			(layer "B.Fab")
			(effects
				(font
					(size 1.27 1.27)
				)
				(justify mirror)
			)
		)
		(duplicate_pad_numbers_are_jumpers no)
		(fp_poly
			(pts
				(xy 0.7239 -0.2159) (xy -0.7239 -0.2159) (xy -0.7239 1.9939) (xy 0.7239 1.9939)
			)
			(stroke
				(width 0)
				(type default)
			)
			(fill no)
			(layer "B.CrtYd")
		)
		(fp_line
			(start -0.7239 -0.2159)
			(end 0.7239 -0.2159)
			(stroke
				(width 0.1)
				(type default)
			)
			(layer "B.Fab")
		)
		(fp_line
			(start -0.7239 1.9939)
			(end -0.7239 -0.2159)
			(stroke
				(width 0.1)
				(type default)
			)
			(layer "B.Fab")
		)
		(fp_line
			(start 0.7239 -0.2159)
			(end 0.7239 1.9939)
			(stroke
				(width 0.1)
				(type default)
			)
			(layer "B.Fab")
		)
		(fp_line
			(start 0.7239 1.9939)
			(end -0.7239 1.9939)
			(stroke
				(width 0.1)
				(type default)
			)
			(layer "B.Fab")
		)
		(pad "1" smd rect
			(at 0 0 180)
			(size 1.27 1.016)
			(layers "B.Cu" "B.Mask" "B.Paste")
			(net "PVCCIN_CPU0")
		)
		(pad "2" smd rect
			(at 0 1.778 180)
			(size 1.27 1.016)
			(layers "B.Cu" "B.Mask" "B.Paste")
			(net "GND")
		)
		(zone
			(layer "B.Cu")
			(hatch none 0.5)
			(connect_pads
				(clearance 0)
			)
			(min_thickness 0.25)
			(keepout
				(tracks not_allowed)
				(vias allowed)
				(pads allowed)
				(copperpour not_allowed)
				(footprints allowed)
			)
			(placement
				(enabled no)
				(sheetname "")
			)
			(fill
				(thermal_gap 0.5)
				(thermal_bridge_width 0.5)
				(island_removal_mode 0)
			)
			(polygon
				(pts
					(xy 268.327886 -77.32014) (xy 267.057886 -77.32014) (xy 267.057886 -76.55814) (xy 268.327886 -76.55814)
				)
			)
		)
	)
	(footprint ""
		(layer "B.Cu")
		(at 387.689598 -34.655506 -90)
		(property "Reference" "R7W6"
			(at 0.8382 -0.67818 270)
			(unlocked yes)
			(layer "B.SilkS")
			(effects
				(font
					(size 0.4064 0.254)
					(thickness 0.1524)
				)
				(justify left mirror)
			)
		)
		(property "Value" ""
			(at 0 0 90)
			(layer "B.Fab")
			(effects
				(font
					(size 1.27 1.27)
				)
				(justify mirror)
			)
		)
		(duplicate_pad_numbers_are_jumpers no)
		(fp_poly
			(pts
				(xy 0.2794 -0.1016) (xy -0.2794 -0.1016) (xy -0.2794 0.9906) (xy 0.2794 0.9906)
			)
			(stroke
				(width 0)
				(type default)
			)
			(fill no)
			(layer "B.CrtYd")
		)
		(fp_line
			(start -0.2794 0.9906)
			(end -0.2794 -0.1016)
			(stroke
				(width 0.1)
				(type default)
			)
			(layer "B.Fab")
		)
		(fp_line
			(start 0.2794 0.9906)
			(end -0.2794 0.9906)
			(stroke
				(width 0.1)
				(type default)
			)
			(layer "B.Fab")
		)
		(fp_line
			(start -0.2794 -0.1016)
			(end 0.2794 -0.1016)
			(stroke
				(width 0.1)
				(type default)
			)
			(layer "B.Fab")
		)
		(fp_line
			(start 0.2794 -0.1016)
			(end 0.2794 0.9906)
			(stroke
				(width 0.1)
				(type default)
			)
			(layer "B.Fab")
		)
		(pad "1" smd rect
			(at 0 0 90)
			(size 0.508 0.508)
			(layers "B.Cu" "B.Mask" "B.Paste")
			(net "FM_BATTERY_SENSE_EN_N")
		)
		(pad "2" smd rect
			(at 0 0.889 90)
			(size 0.508 0.508)
			(layers "B.Cu" "B.Mask" "B.Paste")
			(net "FM_BATTERY_SENSE_EN_R_N")
		)
		(zone
			(layer "B.Cu")
			(hatch none 0.5)
			(connect_pads
				(clearance 0)
			)
			(min_thickness 0.25)
			(keepout
				(tracks not_allowed)
				(vias allowed)
				(pads allowed)
				(copperpour not_allowed)
				(footprints allowed)
			)
			(placement
				(enabled no)
				(sheetname "")
			)
			(fill
				(thermal_gap 0.5)
				(thermal_bridge_width 0.5)
				(island_removal_mode 0)
			)
			(polygon
				(pts
					(xy 387.054598 -34.401506) (xy 387.054598 -34.909506) (xy 387.435598 -34.909506) (xy 387.435598 -34.401506)
				)
			)
		)
		(zone
			(layer "B.Cu")
			(hatch none 0.5)
			(connect_pads
				(clearance 0)
			)
			(min_thickness 0.25)
			(keepout
				(tracks allowed)
				(vias not_allowed)
				(pads allowed)
				(copperpour not_allowed)
				(footprints allowed)
			)
			(placement
				(enabled no)
				(sheetname "")
			)
			(fill
				(thermal_gap 0.5)
				(thermal_bridge_width 0.5)
				(island_removal_mode 0)
			)
			(polygon
				(pts
					(xy 387.435598 -34.401506) (xy 387.435598 -34.909506) (xy 387.054598 -34.909506) (xy 387.054598 -34.401506)
				)
			)
		)
	)
)
